#ISCELL
  mstr_misc dns *
  *
#ISCELL
  mstr_symbols cad_note *
  *
#ISCELL
  mstr_symbols design_note *
  *
#ISCELL
  mstr_symbols intel_corp_bpage *
  *
#CELL
  dev_discrete cap_a *
  page196_i102
#CELL
  mstr_discrete diode *
  page196_i103
#CELL
  mstr_vreg tps3700 *
  page196_i104
#CELL
  dev_discrete cap_a *
  page196_i105
#CELL
  mstr_discrete res *
  page196_i106
#ISCELL
  mstr_standard offpage *
  page196_i107
#ISCELL
  mstr_symbols gnd *
  page196_i108
#ISCELL
  mstr_symbols gnd *
  page196_i110
#ISCELL
  mstr_symbols p3v3_stby *
  page196_i111
#CELL
  mstr_discrete res *
  page196_i112
#CELL
  mstr_discrete res *
  page196_i113
#CELL
  mstr_discrete res *
  page196_i114
#CELL
  mstr_discrete res *
  page196_i115
#ISCELL
  mstr_symbols p5v *
  page196_i116
#ISCELL
  mstr_symbols p12v *
  page196_i117
#ISCELL
  mstr_symbols gnd *
  page196_i118
#ISCELL
  mstr_symbols gnd *
  page196_i119
#CELL
  mstr_discrete res *
  page196_i120
#CELL
  mstr_discrete res *
  page196_i121
#CELL
  mstr_discrete res *
  page196_i122
#ISCELL
  mstr_symbols p3v3_stby *
  page196_i123
#CELL
  mstr_discrete fet_n *
  page196_i124
#ISCELL
  mstr_symbols gnd *
  page196_i125
#ISCELL
  mstr_symbols p3v3_stby *
  page196_i126
#ISCELL
  mstr_symbols p3v3_stby *
  page196_i127
#CELL
  mstr_discrete diode *
  page196_i128
#ISCELL
  mstr_symbols gnd *
  page196_i43
#ISCELL
  mstr_standard offpage *
  page196_i45
#CELL
  mstr_discrete res *
  page196_i46
#CELL
  mstr_misc battery *
  page196_i47
#CELL
  mstr_discrete vert_batt_3pin *
  page196_i51
#ISCELL
  mstr_symbols gnd *
  page196_i52
#CELL
  mstr_discrete diode2a_dual *
  page196_i53
#ISCELL
  mstr_symbols p3v3_stby *
  page196_i54
#ISCELL
  mstr_symbols p3v3_stby *
  page196_i56
#ISCELL
  mstr_symbols p12v_stby *
  page196_i57
#ISCELL
  mstr_symbols p3v3_stby *
  page196_i58
#CELL
  mstr_discrete res *
  page196_i59
#CELL
  mstr_discrete cap *
  page196_i60
#ISCELL
  mstr_symbols gnd *
  page196_i61
#ISCELL
  mstr_symbols gnd *
  page196_i62
#ISCELL
  mstr_standard offpage *
  page196_i63
#ISCELL
  mstr_standard offpage *
  page196_i64
#CELL
  mstr_discrete res *
  page196_i65
#CELL
  mstr_discrete res *
  page196_i68
#ISCELL
  mstr_symbols p3v3_stby *
  page196_i69
#CELL
  mstr_analog adm1085 *
  page196_i70
#CELL
  mstr_discrete res *
  page196_i71
#CELL
  dev_discrete cap_a *
  page196_i72
#ISCELL
  mstr_symbols gnd *
  page196_i73
#CELL
  mstr_discrete res *
  page196_i74
#CELL
  mstr_discrete res *
  page196_i75
#ISCELL
  mstr_symbols gnd *
  page196_i76
#CELL
  mstr_analog adm809 *
  page196_i80
#CELL
  dev_discrete cap_a *
  page196_i81
#ISCELL
  mstr_symbols gnd *
  page196_i82
#ISCELL
  mstr_symbols p3v3 *
  page196_i83
#ISCELL
  mstr_standard offpage *
  page196_i88
#CELL
  mstr_analog adm809 *
  page196_i89
#CELL
  mstr_discrete res *
  page196_i90
#ISCELL
  mstr_standard offpage *
  page196_i91
#CELL
  dev_discrete cap_a *
  page196_i94
#ISCELL
  mstr_symbols gnd *
  page196_i95
#ISCELL
  mstr_standard offpage *
  page196_i96
#ISCELL
  mstr_symbols p3v3_rtc_stby *
  page196_i97
#ISCELL
  mstr_standard offpage *
  page196_i98
